# T6G (Grand Teton) — schematic netlist excerpt (pin names and nets, part order shuffled) for the footprints in the layout excerpt that follows; sources: Cadence DE-HDL packaged netlist, KiCad conversion of 04192023_DAF0TMB3IC0_F0TG_MB_C_brd_V02_OCP.brd

J23  SCONN288_DDR506112002KQ  IO  pkg DDR288S_1-1VXC  page 91
  VIN_BULK0  = P12V_MEM_CPU0
  RFU0  = NC
  VIN_MGMT  = P3V3_AUX
  HSCL  = I3C_SPD_DDRF_CPU0_SCL
  HSDA  = I3C_SPD_DDRF_CPU0_SDA
  VSS0  = GND
  DQ0_A  = M_F_CPU0_SA_DQ<0>
  VSS1  = GND
  DQ1_A  = M_F_CPU0_SA_DQ<1>
  VSS2  = GND
  DQS0_A_T  = M_F_CPU0_SA_DQS_DP<0>
  DQS0_A_C  = M_F_CPU0_SA_DQS_DN<0>
  VSS3  = GND
  DQ4_A  = M_F_CPU0_SA_DQ<4>
  VSS4  = GND
  DQ5_A  = M_F_CPU0_SA_DQ<5>
  VSS5  = GND
  DQ8_A  = M_F_CPU0_SA_DQ<8>
  VSS6  = GND
  DQ9_A  = M_F_CPU0_SA_DQ<9>
  VSS7  = GND
  DQS1_A_T  = M_F_CPU0_SA_DQS_DP<1>
  DQS1_A_C  = M_F_CPU0_SA_DQS_DN<1>
  VSS8  = GND
  DQ12_A  = M_F_CPU0_SA_DQ<12>
  VSS9  = GND
  DQ13_A  = M_F_CPU0_SA_DQ<13>
  VSS10  = GND
  DQ16_A  = M_F_CPU0_SA_DQ<16>
  VSS11  = GND
  DQ17_A  = M_F_CPU0_SA_DQ<17>
  VSS12  = GND
  DQS2_A_T  = M_F_CPU0_SA_DQS_DP<2>
  DQS2_A_C  = M_F_CPU0_SA_DQS_DN<2>
  VSS13  = GND
  DQ20_A  = M_F_CPU0_SA_DQ<20>
  VSS14  = GND
  DQ21_A  = M_F_CPU0_SA_DQ<21>
  VSS15  = GND
  DQ24_A  = M_F_CPU0_SA_DQ<24>
  VSS16  = GND
  DQ25_A  = M_F_CPU0_SA_DQ<25>
  VSS17  = GND
  DQS3_A_T  = M_F_CPU0_SA_DQS_DP<3>
  DQS3_A_C  = M_F_CPU0_SA_DQS_DN<3>
  VSS18  = GND
  DQ28_A  = M_F_CPU0_SA_DQ<28>
  VSS19  = GND
  DQ29_A  = M_F_CPU0_SA_DQ<29>
  VSS20  = GND
  CB0_A  = M_F_CPU0_SA_CB<0>
  VSS21  = GND
  CB1_A  = M_F_CPU0_SA_CB<1>
  VSS22  = GND
  DQS4_A_T  = M_F_CPU0_SA_DQS_DP<4>
  DQS4_A_C  = M_F_CPU0_SA_DQS_DN<4>
  VSS23  = GND
  CB4_A  = M_F_CPU0_SA_CB<4>
  VSS24  = GND
  CB5_A  = M_F_CPU0_SA_CB<5>
  VSS25  = GND
  ALERT_N  = M_F_CPU0_ALERT_N
  VSS26  = GND
  CS0_A_N  = M_F_CPU0_SA_CS_N<0>
  VSS27  = GND
  CA0_A  = M_F_CPU0_SA_CA<0>
  VSS28  = GND
  CA2_A  = M_F_CPU0_SA_CA<2>
  VSS29  = GND
  CA4_A  = M_F_CPU0_SA_CA<4>
  VSS30  = GND
  CA6_A  = M_F_CPU0_SA_CA<6>
  VSS31  = GND
  PAR_A  = M_F_CPU0_SA_PAR
  VSS32  = GND
  CA0_B  = M_F_CPU0_SB_CA<0>
  VSS33  = GND
  CA2_B  = M_F_CPU0_SB_CA<2>
  VSS34  = GND
  CA4_B  = M_F_CPU0_SB_CA<4>
  VSS35  = GND
  CA6_B  = M_F_CPU0_SB_CA<6>
  VSS36  = GND
  CS0_B_N  = M_F_CPU0_SB_CS_N<0>
  VSS37  = GND
  \lbd||rsp_a_n\  = M_F_CPU0_SA_RSP<0>
  \lbs||rsp_b_n\  = M_F_CPU0_SB_RSP<0>
  VSS38  = GND
  CB4_B  = M_F_CPU0_SB_CB<4>
  VSS39  = GND
  CB5_B  = M_F_CPU0_SB_CB<5>
  VSS40  = GND
  \dqs9_b_t||tdqs9_b_t||dbi4_b_n\  = M_F_CPU0_SB_DQS_DP<9>
  \dqs9_b_c||tdqs9_b_c\  = M_F_CPU0_SB_DQS_DN<9>
  VSS41  = GND
  CB0_B  = M_F_CPU0_SB_CB<0>
  VSS42  = GND
  CB1_B  = M_F_CPU0_SB_CB<1>
  VSS43  = GND
  DQ0_B  = M_F_CPU0_SB_DQ<0>
  VSS44  = GND
  DQ1_B  = M_F_CPU0_SB_DQ<1>
  VSS45  = GND
  DQS0_B_T  = M_F_CPU0_SB_DQS_DP<0>
  DQS0_B_C  = M_F_CPU0_SB_DQS_DN<0>
  VSS46  = GND
  DQ4_B  = M_F_CPU0_SB_DQ<4>
  VSS47  = GND
  DQ5_B  = M_F_CPU0_SB_DQ<5>
  VSS48  = GND
  DQ8_B  = M_F_CPU0_SB_DQ<8>
  VSS49  = GND
  DQ9_B  = M_F_CPU0_SB_DQ<9>
  VSS50  = GND
  DQS1_B_T  = M_F_CPU0_SB_DQS_DP<1>
  DQS1_B_C  = M_F_CPU0_SB_DQS_DN<1>
  VSS51  = GND
  DQ12_B  = M_F_CPU0_SB_DQ<12>
  VSS52  = GND
  DQ13_B  = M_F_CPU0_SB_DQ<13>
  VSS53  = GND
  DQ16_B  = M_F_CPU0_SB_DQ<16>
  VSS54  = GND
  DQ17_B  = M_F_CPU0_SB_DQ<17>
  VSS55  = GND
  DQS2_B_T  = M_F_CPU0_SB_DQS_DP<2>
  DQS2_B_C  = M_F_CPU0_SB_DQS_DN<2>
  VSS56  = GND
  DQ20_B  = M_F_CPU0_SB_DQ<20>
  VSS57  = GND
  DQ21_B  = M_F_CPU0_SB_DQ<21>
  VSS58  = GND
  DQ24_B  = M_F_CPU0_SB_DQ<24>
  VSS59  = GND
  DQ25_B  = M_F_CPU0_SB_DQ<25>
  VSS60  = GND
  DQS3_B_T  = M_F_CPU0_SB_DQS_DP<3>
  DQS3_B_C  = M_F_CPU0_SB_DQS_DN<3>
  VSS61  = GND
  DQ28_B  = M_F_CPU0_SB_DQ<28>
  VSS62  = GND
  DQ29_B  = M_F_CPU0_SB_DQ<29>
  VSS63  = GND
  RFU1  = NC
  VIN_BULK1  = P12V_MEM_CPU0
  VIN_BULK2  = P12V_MEM_CPU0
  \pwr_good||fail_n\  = PWRGD_CHF_CPU0_DIMM
  HAS  = PD_CHF_CPU0_DIMM_SAA
  RFU2  = NC
  RFU3  = NC
  VSS64  = GND
  DQ2_A  = M_F_CPU0_SA_DQ<2>
  VSS65  = GND
  DQ3_A  = M_F_CPU0_SA_DQ<3>
  VSS66  = GND
  \dqs5_a_c||tdqs5_a_c||dqs5_a_t||tdqs5_a_t\  = M_F_CPU0_SA_DQS_DN<5>
  \dqs5_a_t||tdqs5_a_t\  = M_F_CPU0_SA_DQS_DP<5>
  VSS67  = GND
  DQ6_A  = M_F_CPU0_SA_DQ<6>
  VSS68  = GND
  DQ7_A  = M_F_CPU0_SA_DQ<7>
  VSS69  = GND
  DQ10_A  = M_F_CPU0_SA_DQ<10>
  VSS70  = GND
  DQ11_A  = M_F_CPU0_SA_DQ<11>
  VSS71  = GND
  \dqs6_a_c||tdqs6_a_c||dqs6_a_t||tdqs6_a_t\  = M_F_CPU0_SA_DQS_DN<6>
  \dqs6_a_t||tdqs6_a_t\  = M_F_CPU0_SA_DQS_DP<6>
  VSS72  = GND
  DQ14_A  = M_F_CPU0_SA_DQ<14>
  VSS73  = GND
  DQ15_A  = M_F_CPU0_SA_DQ<15>
  VSS74  = GND
  DQ18_A  = M_F_CPU0_SA_DQ<18>
  VSS75  = GND
  DQ19_A  = M_F_CPU0_SA_DQ<19>
  VSS76  = GND
  \dqs7_a_c||tdqs7_a_c\  = M_F_CPU0_SA_DQS_DN<7>
  \dqs7_a_t||tdqs7_a_t\  = M_F_CPU0_SA_DQS_DP<7>
  VSS77  = GND
  DQ22_A  = M_F_CPU0_SA_DQ<22>
  VSS78  = GND
  DQ23_A  = M_F_CPU0_SA_DQ<23>
  VSS79  = GND
  DQ26_A  = M_F_CPU0_SA_DQ<26>
  VSS80  = GND
  DQ27_A  = M_F_CPU0_SA_DQ<27>
  VSS81  = GND
  \dqs8_a_c||tdqs8_a_c\  = M_F_CPU0_SA_DQS_DN<8>
  \dqs8_a_t||tdqs8_a_t\  = M_F_CPU0_SA_DQS_DP<8>
  VSS82  = GND
  DQ30_A  = M_F_CPU0_SA_DQ<30>
  VSS83  = GND
  DQ31_A  = M_F_CPU0_SA_DQ<31>
  VSS84  = GND
  CB2_A  = M_F_CPU0_SA_CB<2>
  VSS85  = GND
  CB3_A  = M_F_CPU0_SA_CB<3>
  VSS86  = GND
  \dqs9_a_c||tdqs9_a_c\  = M_F_CPU0_SA_DQS_DN<9>
  \dqs9_a_t||tdqs9_a_t\  = M_F_CPU0_SA_DQS_DP<9>
  VSS87  = GND
  CB6_A  = M_F_CPU0_SA_CB<6>
  VSS88  = GND
  CB7_A  = M_F_CPU0_SA_CB<7>
  VSS89  = GND
  RESET_N  = M_F_CPU0_RESET_N
  VSS90  = GND
  CS1_A_N  = M_F_CPU0_SA_CS_N<1>
  VSS91  = GND
  CA1_A  = M_F_CPU0_SA_CA<1>
  VSS92  = GND
  CA3_A  = M_F_CPU0_SA_CA<3>
  VSS93  = GND
  CA5_A  = M_F_CPU0_SA_CA<5>
  VSS94  = GND
  CK_T  = M_F_CPU0_CLK_DP<0>
  CK_C  = M_F_CPU0_CLK_DN<0>
  VSS95  = GND
  RFU4  = NC
  CA1_B  = M_F_CPU0_SB_CA<1>
  VSS96  = GND
  CA3_B  = M_F_CPU0_SB_CA<3>
  VSS97  = GND
  CA5_B  = M_F_CPU0_SB_CA<5>
  VSS98  = GND
  PAR_B  = M_F_CPU0_SB_PAR
  VSS99  = GND
  CS1_B_N  = M_F_CPU0_SB_CS_N<1>
  VSS100  = GND
  RFU5  = NC
  RFU6  = NC
  VSS101  = GND
  CB6_B  = M_F_CPU0_SB_CB<6>
  VSS102  = GND
  CB7_B  = M_F_CPU0_SB_CB<7>
  VSS103  = GND
  DQS4_B_C  = M_F_CPU0_SB_DQS_DN<4>
  DQS4_B_T  = M_F_CPU0_SB_DQS_DP<4>
  VSS104  = GND
  CB2_B  = M_F_CPU0_SB_CB<2>
  VSS105  = GND
  CB3_B  = M_F_CPU0_SB_CB<3>
  VSS106  = GND
  DQ2_B  = M_F_CPU0_SB_DQ<2>
  VSS107  = GND
  DQ3_B  = M_F_CPU0_SB_DQ<3>
  VSS108  = GND
  \dqs5_b_c||tdqs5_b_c\  = M_F_CPU0_SB_DQS_DN<5>
  \dqs5_b_t||tdqs5_b_t\  = M_F_CPU0_SB_DQS_DP<5>
  VSS109  = GND
  DQ6_B  = M_F_CPU0_SB_DQ<6>
  VSS110  = GND
  DQ7_B  = M_F_CPU0_SB_DQ<7>
  VSS111  = GND
  DQ10_B  = M_F_CPU0_SB_DQ<10>
  VSS112  = GND
  DQ11_B  = M_F_CPU0_SB_DQ<11>
  VSS113  = GND
  \dqs6_b_c||tdqs6_b_c\  = M_F_CPU0_SB_DQS_DN<6>
  \dqs6_b_t||tdqs6_b_t\  = M_F_CPU0_SB_DQS_DP<6>
  VSS114  = GND
  DQ14_B  = M_F_CPU0_SB_DQ<14>
  VSS115  = GND
  DQ15_B  = M_F_CPU0_SB_DQ<15>
  VSS116  = GND
  DQ18_B  = M_F_CPU0_SB_DQ<18>
  VSS117  = GND
  DQ19_B  = M_F_CPU0_SB_DQ<19>
  VSS118  = GND
  \dqs7_b_c||tdqs7_b_c\  = M_F_CPU0_SB_DQS_DN<7>
  \dqs7_b_t||tdqs7_b_t\  = M_F_CPU0_SB_DQS_DP<7>
  VSS119  = GND
  DQ22_B  = M_F_CPU0_SB_DQ<22>
  VSS120  = GND
  DQ23_B  = M_F_CPU0_SB_DQ<23>
  VSS121  = GND
  DQ26_B  = M_F_CPU0_SB_DQ<26>
  VSS122  = GND
  DQ27_B  = M_F_CPU0_SB_DQ<27>
  VSS123  = GND
  \dqs8_b_c||tdqs8_b_c\  = M_F_CPU0_SB_DQS_DN<8>
  \dqs8_b_t||tdqs8_b_t\  = M_F_CPU0_SB_DQS_DP<8>
  VSS124  = GND
  DQ30_B  = M_F_CPU0_SB_DQ<30>
  VSS125  = GND
  DQ31_B  = M_F_CPU0_SB_DQ<31>
  VSS126  = GND
  G1  = GND
  G2  = GND
  G3  = GND

(kicad_pcb
	(version 20260206)
	(generator "pcbnew")
	(generator_version "10.0")
	(general
		(thickness 1.6)
		(legacy_teardrops no)
	)
	(paper "A4")
	(title_block
		(title "04192023_DAF0TMB3IC0_F0TG_MB_C_brd_V02_OCP.brd")
		(comment 1 "Grand Teton / footprint 2449 of 8354 (J23), pads 277-291 of 291")
	)
	(layers
		(0 "F.Cu" signal "TOP")
		(4 "In1.Cu" signal "GND")
		(6 "In2.Cu" signal "IN1")
		(8 "In3.Cu" signal "GND1")
		(10 "In4.Cu" signal "IN2")
		(12 "In5.Cu" signal "GND2")
		(14 "In6.Cu" signal "IN3")
		(16 "In7.Cu" signal "GND3")
		(18 "In8.Cu" signal "VCC")
		(20 "In9.Cu" signal "VCC1")
		(22 "In10.Cu" signal "GND4")
		(24 "In11.Cu" signal "IN4")
		(26 "In12.Cu" signal "GND5")
		(28 "In13.Cu" signal "IN5")
		(30 "In14.Cu" signal "GND6")
		(32 "In15.Cu" signal "IN6")
		(34 "In16.Cu" signal "GND7")
		(2 "B.Cu" signal "BOTTOM")
		(9 "F.Adhes" user "F.Adhesive")
		(11 "B.Adhes" user "B.Adhesive")
		(13 "F.Paste" user "Package Geometry/Pastemask Top")
		(15 "B.Paste" user "Package Geometry/Pastemask Bottom")
		(5 "F.SilkS" user "Ref Des/Silkscreen Top")
		(7 "B.SilkS" user "Ref Des/Silkscreen Bottom")
		(1 "F.Mask" user "Board Geometry/Soldermask Top")
		(3 "B.Mask" user "Board Geometry/Soldermask Bottom")
		(17 "Dwgs.User" user "User.Drawings")
		(19 "Cmts.User" user "User.Comments")
		(21 "Eco1.User" user "User.Eco1")
		(23 "Eco2.User" user "User.Eco2")
		(25 "Edge.Cuts" user "Board Geometry/Outline")
		(27 "Margin" user)
		(31 "F.CrtYd" user "Package Geometry/Place Bound Top")
		(29 "B.CrtYd" user "Package Geometry/Place Bound Bottom")
		(35 "F.Fab" user "Ref Des/Assembly Top")
		(33 "B.Fab" user "Ref Des/Assembly Bottom")
	)
	(footprint ""
		(layer "F.Cu")
		(at 267.598144 -255.560068 180)
		(property "Reference" "J23"
			(at -2.2098 -81.984088 0)
			(unlocked yes)
			(layer "F.SilkS")
			(effects
				(font
					(size 0.7874 0.5842)
					(thickness 0.1524)
				)
			)
		)
		(property "Value" ""
			(at 0 0 180)
			(layer "F.Fab")
			(effects
				(font
					(size 1.27 1.27)
				)
			)
		)
		(duplicate_pad_numbers_are_jumpers no)
		(pad "277" smd rect
			(at 2.050034 53.975 90)
			(size 0.519938 1.4986)
			(layers "F.Cu" "F.Mask" "F.Paste")
			(net "GND")
		)
		(pad "278" smd rect
			(at 2.050034 54.824884 90)
			(size 0.519938 1.4986)
			(layers "F.Cu" "F.Mask" "F.Paste")
			(net "M_F_CPU0_SB_DQ<26>")
		)
		(pad "279" smd rect
			(at 2.050034 55.675022 90)
			(size 0.519938 1.4986)
			(layers "F.Cu" "F.Mask" "F.Paste")
			(net "GND")
		)
		(pad "280" smd rect
			(at 2.050034 56.524906 90)
			(size 0.519938 1.4986)
			(layers "F.Cu" "F.Mask" "F.Paste")
			(net "M_F_CPU0_SB_DQ<27>")
		)
		(pad "281" smd rect
			(at 2.050034 57.375044 90)
			(size 0.519938 1.4986)
			(layers "F.Cu" "F.Mask" "F.Paste")
			(net "GND")
		)
		(pad "282" smd rect
			(at 2.050034 58.224928 90)
			(size 0.519938 1.4986)
			(layers "F.Cu" "F.Mask" "F.Paste")
			(net "M_F_CPU0_SB_DQS_DN<8>")
		)
		(pad "283" smd rect
			(at 2.050034 59.075066 90)
			(size 0.519938 1.4986)
			(layers "F.Cu" "F.Mask" "F.Paste")
			(net "M_F_CPU0_SB_DQS_DP<8>")
		)
		(pad "284" smd rect
			(at 2.050034 59.92495 90)
			(size 0.519938 1.4986)
			(layers "F.Cu" "F.Mask" "F.Paste")
			(net "GND")
		)
		(pad "285" smd rect
			(at 2.050034 60.775088 90)
			(size 0.519938 1.4986)
			(layers "F.Cu" "F.Mask" "F.Paste")
			(net "M_F_CPU0_SB_DQ<30>")
		)
		(pad "286" smd rect
			(at 2.050034 61.624972 90)
			(size 0.519938 1.4986)
			(layers "F.Cu" "F.Mask" "F.Paste")
			(net "GND")
		)
		(pad "287" smd rect
			(at 2.050034 62.47511 90)
			(size 0.519938 1.4986)
			(layers "F.Cu" "F.Mask" "F.Paste")
			(net "M_F_CPU0_SB_DQ<31>")
		)
		(pad "288" smd rect
			(at 2.050034 63.324994 90)
			(size 0.519938 1.4986)
			(layers "F.Cu" "F.Mask" "F.Paste")
			(net "GND")
		)
		(pad "G1" thru_hole oval
			(at 0 -68.97497 90)
			(size 1.7272 3.4798)
			(drill oval 1.2192 2.4638)
			(layers "*.Cu" "*.Mask")
			(remove_unused_layers no)
			(net "GND")
			(clearance 0.127)
			(thermal_gap 0.127)
		)
		(pad "G2" thru_hole oval
			(at 0 3.875024 90)
			(size 1.7272 3.4798)
			(drill oval 1.2192 2.4638)
			(layers "*.Cu" "*.Mask")
			(remove_unused_layers no)
			(net "GND")
			(clearance 0.127)
			(thermal_gap 0.127)
		)
		(pad "G3" thru_hole oval
			(at 0 68.97497 90)
			(size 1.7272 3.4798)
			(drill oval 1.2192 2.4638)
			(layers "*.Cu" "*.Mask")
			(remove_unused_layers no)
			(net "GND")
			(clearance 0.127)
			(thermal_gap 0.127)
		)
	)
)
